(kicad_pcb
	(version 20260206)
	(generator "pcbnew")
	(generator_version "10.0")
	(general
		(thickness 1.6)
		(legacy_teardrops no)
	)
	(paper "A4")
	(title_block
		(title "01162023_DA0F0TEBIF0_F0T_Expander_BD_F_brd_V02_OCP.brd")
		(comment 1 "Grand Teton / footprints 1577-1583 of 9728")
	)
	(layers
		(0 "F.Cu" signal "TOP")
		(4 "In1.Cu" signal "GND")
		(6 "In2.Cu" signal "VCC")
		(8 "In3.Cu" signal "VCC1")
		(10 "In4.Cu" signal "GND1")
		(12 "In5.Cu" signal "IN1")
		(14 "In6.Cu" signal "GND2")
		(16 "In7.Cu" signal "IN2")
		(18 "In8.Cu" signal "GND3")
		(20 "In9.Cu" signal "IN3")
		(22 "In10.Cu" signal "GND4")
		(24 "In11.Cu" signal "IN4")
		(26 "In12.Cu" signal "GND5")
		(28 "In13.Cu" signal "IN5")
		(30 "In14.Cu" signal "GND6")
		(32 "In15.Cu" signal "IN6")
		(34 "In16.Cu" signal "GND7")
		(2 "B.Cu" signal "BOTTOM")
		(9 "F.Adhes" user "F.Adhesive")
		(11 "B.Adhes" user "B.Adhesive")
		(13 "F.Paste" user "Package Geometry/Pastemask Top")
		(15 "B.Paste" user "Package Geometry/Pastemask Bottom")
		(5 "F.SilkS" user "Ref Des/Silkscreen Top")
		(7 "B.SilkS" user "Ref Des/Silkscreen Bottom")
		(1 "F.Mask" user "Board Geometry/Soldermask Top")
		(3 "B.Mask" user "Board Geometry/Soldermask Bottom")
		(17 "Dwgs.User" user "User.Drawings")
		(19 "Cmts.User" user "User.Comments")
		(21 "Eco1.User" user "User.Eco1")
		(23 "Eco2.User" user "User.Eco2")
		(25 "Edge.Cuts" user "Board Geometry/Outline")
		(27 "Margin" user)
		(31 "F.CrtYd" user "Package Geometry/Place Bound Top")
		(29 "B.CrtYd" user "Package Geometry/Place Bound Bottom")
		(35 "F.Fab" user "Ref Des/Assembly Top")
		(33 "B.Fab" user "Ref Des/Assembly Bottom")
	)
	(footprint ""
		(layer "F.Cu")
		(at 124.733812 -156.288994 -90)
		(property "Reference" "PR6894"
			(at 0 0 270)
			(layer "F.SilkS")
			(hide yes)
			(effects
				(font
					(size 1.27 1.27)
				)
			)
		)
		(property "Value" ""
			(at 0 0 270)
			(layer "F.Fab")
			(effects
				(font
					(size 1.27 1.27)
				)
			)
		)
		(duplicate_pad_numbers_are_jumpers no)
		(fp_line
			(start -0.7874 0.4064)
			(end -0.7874 -0.4064)
			(stroke
				(width 0.1524)
				(type default)
			)
			(layer "F.SilkS")
		)
		(fp_line
			(start 0.7874 0.4064)
			(end -0.7874 0.4064)
			(stroke
				(width 0.1524)
				(type default)
			)
			(layer "F.SilkS")
		)
		(fp_line
			(start -0.7874 -0.4064)
			(end 0.7874 -0.4064)
			(stroke
				(width 0.1524)
				(type default)
			)
			(layer "F.SilkS")
		)
		(fp_line
			(start 0.7874 -0.4064)
			(end 0.7874 0.4064)
			(stroke
				(width 0.1524)
				(type default)
			)
			(layer "F.SilkS")
		)
		(fp_line
			(start -0.67945 0.3048)
			(end -0.67945 -0.305054)
			(stroke
				(width 0.1)
				(type default)
			)
			(layer "F.Fab")
		)
		(fp_line
			(start -0.12065 0.3048)
			(end -0.67945 0.3048)
			(stroke
				(width 0.1)
				(type default)
			)
			(layer "F.Fab")
		)
		(fp_line
			(start 0.120396 0.3048)
			(end 0.120396 0.2794)
			(stroke
				(width 0.1)
				(type default)
			)
			(layer "F.Fab")
		)
		(fp_line
			(start 0.67945 0.3048)
			(end 0.120396 0.3048)
			(stroke
				(width 0.1)
				(type default)
			)
			(layer "F.Fab")
		)
		(fp_line
			(start -0.12065 0.2794)
			(end -0.12065 0.3048)
			(stroke
				(width 0.1)
				(type default)
			)
			(layer "F.Fab")
		)
		(fp_line
			(start 0.120396 0.2794)
			(end -0.12065 0.2794)
			(stroke
				(width 0.1)
				(type default)
			)
			(layer "F.Fab")
		)
		(fp_line
			(start -0.12065 -0.2794)
			(end 0.12065 -0.2794)
			(stroke
				(width 0.1)
				(type default)
			)
			(layer "F.Fab")
		)
		(fp_line
			(start 0.12065 -0.2794)
			(end 0.12065 -0.3048)
			(stroke
				(width 0.1)
				(type default)
			)
			(layer "F.Fab")
		)
		(fp_line
			(start 0.12065 -0.3048)
			(end 0.67945 -0.3048)
			(stroke
				(width 0.1)
				(type default)
			)
			(layer "F.Fab")
		)
		(fp_line
			(start 0.67945 -0.3048)
			(end 0.67945 0.3048)
			(stroke
				(width 0.1)
				(type default)
			)
			(layer "F.Fab")
		)
		(fp_line
			(start -0.67945 -0.305054)
			(end -0.12065 -0.305054)
			(stroke
				(width 0.1)
				(type default)
			)
			(layer "F.Fab")
		)
		(fp_line
			(start -0.12065 -0.305054)
			(end -0.12065 -0.2794)
			(stroke
				(width 0.1)
				(type default)
			)
			(layer "F.Fab")
		)
		(pad "1" smd circle
			(at -0.40005 0 270)
			(size 0 0)
			(layers "F.Cu" "F.Mask" "F.Paste")
			(net "P12V_NIC2_CO_OV_FB")
		)
		(pad "2" smd circle
			(at 0.40005 0 270)
			(size 0 0)
			(layers "F.Cu" "F.Mask" "F.Paste")
			(net "GND")
		)
	)
	(footprint ""
		(layer "F.Cu")
		(at 434.410358 -63.652146 180)
		(property "Reference" "R6027"
			(at 0 0 180)
			(layer "F.SilkS")
			(hide yes)
			(effects
				(font
					(size 1.27 1.27)
				)
			)
		)
		(property "Value" ""
			(at 0 0 180)
			(layer "F.Fab")
			(effects
				(font
					(size 1.27 1.27)
				)
			)
		)
		(duplicate_pad_numbers_are_jumpers no)
		(fp_line
			(start 0.7874 0.4064)
			(end -0.7874 0.4064)
			(stroke
				(width 0.1524)
				(type default)
			)
			(layer "F.SilkS")
		)
		(fp_line
			(start 0.7874 -0.4064)
			(end 0.7874 0.4064)
			(stroke
				(width 0.1524)
				(type default)
			)
			(layer "F.SilkS")
		)
		(fp_line
			(start -0.7874 0.4064)
			(end -0.7874 -0.4064)
			(stroke
				(width 0.1524)
				(type default)
			)
			(layer "F.SilkS")
		)
		(fp_line
			(start -0.7874 -0.4064)
			(end 0.7874 -0.4064)
			(stroke
				(width 0.1524)
				(type default)
			)
			(layer "F.SilkS")
		)
		(fp_line
			(start 0.67945 0.3048)
			(end 0.120396 0.3048)
			(stroke
				(width 0.1)
				(type default)
			)
			(layer "F.Fab")
		)
		(fp_line
			(start 0.67945 -0.3048)
			(end 0.67945 0.3048)
			(stroke
				(width 0.1)
				(type default)
			)
			(layer "F.Fab")
		)
		(fp_line
			(start 0.12065 -0.2794)
			(end 0.12065 -0.3048)
			(stroke
				(width 0.1)
				(type default)
			)
			(layer "F.Fab")
		)
		(fp_line
			(start 0.12065 -0.3048)
			(end 0.67945 -0.3048)
			(stroke
				(width 0.1)
				(type default)
			)
			(layer "F.Fab")
		)
		(fp_line
			(start 0.120396 0.3048)
			(end 0.120396 0.2794)
			(stroke
				(width 0.1)
				(type default)
			)
			(layer "F.Fab")
		)
		(fp_line
			(start 0.120396 0.2794)
			(end -0.12065 0.2794)
			(stroke
				(width 0.1)
				(type default)
			)
			(layer "F.Fab")
		)
		(fp_line
			(start -0.12065 0.3048)
			(end -0.67945 0.3048)
			(stroke
				(width 0.1)
				(type default)
			)
			(layer "F.Fab")
		)
		(fp_line
			(start -0.12065 0.2794)
			(end -0.12065 0.3048)
			(stroke
				(width 0.1)
				(type default)
			)
			(layer "F.Fab")
		)
		(fp_line
			(start -0.12065 -0.2794)
			(end 0.12065 -0.2794)
			(stroke
				(width 0.1)
				(type default)
			)
			(layer "F.Fab")
		)
		(fp_line
			(start -0.12065 -0.305054)
			(end -0.12065 -0.2794)
			(stroke
				(width 0.1)
				(type default)
			)
			(layer "F.Fab")
		)
		(fp_line
			(start -0.67945 0.3048)
			(end -0.67945 -0.305054)
			(stroke
				(width 0.1)
				(type default)
			)
			(layer "F.Fab")
		)
		(fp_line
			(start -0.67945 -0.305054)
			(end -0.12065 -0.305054)
			(stroke
				(width 0.1)
				(type default)
			)
			(layer "F.Fab")
		)
		(pad "1" smd circle
			(at -0.40005 0 180)
			(size 0 0)
			(layers "F.Cu" "F.Mask" "F.Paste")
			(net "P5V_AUX")
		)
		(pad "2" smd circle
			(at 0.40005 0 180)
			(size 0 0)
			(layers "F.Cu" "F.Mask" "F.Paste")
			(net "P12V_SSD15_PG_G2")
		)
	)
	(footprint ""
		(layer "F.Cu")
		(at 393.558014 -72.766682 90)
		(property "Reference" "PC885"
			(at 0 0 90)
			(layer "F.SilkS")
			(hide yes)
			(effects
				(font
					(size 1.27 1.27)
				)
			)
		)
		(property "Value" ""
			(at 0 0 90)
			(layer "F.Fab")
			(effects
				(font
					(size 1.27 1.27)
				)
			)
		)
		(duplicate_pad_numbers_are_jumpers no)
		(fp_line
			(start 0.7874 -0.4064)
			(end 0.7874 0.4064)
			(stroke
				(width 0.1524)
				(type default)
			)
			(layer "F.SilkS")
		)
		(fp_line
			(start -0.7874 -0.4064)
			(end 0.7874 -0.4064)
			(stroke
				(width 0.1524)
				(type default)
			)
			(layer "F.SilkS")
		)
		(fp_line
			(start 0.7874 0.4064)
			(end -0.7874 0.4064)
			(stroke
				(width 0.1524)
				(type default)
			)
			(layer "F.SilkS")
		)
		(fp_line
			(start -0.7874 0.4064)
			(end -0.7874 -0.4064)
			(stroke
				(width 0.1524)
				(type default)
			)
			(layer "F.SilkS")
		)
		(fp_line
			(start -0.12065 -0.305054)
			(end -0.12065 -0.2794)
			(stroke
				(width 0.1)
				(type default)
			)
			(layer "F.Fab")
		)
		(fp_line
			(start -0.67945 -0.305054)
			(end -0.12065 -0.305054)
			(stroke
				(width 0.1)
				(type default)
			)
			(layer "F.Fab")
		)
		(fp_line
			(start 0.67945 -0.3048)
			(end 0.67945 0.3048)
			(stroke
				(width 0.1)
				(type default)
			)
			(layer "F.Fab")
		)
		(fp_line
			(start 0.12065 -0.3048)
			(end 0.67945 -0.3048)
			(stroke
				(width 0.1)
				(type default)
			)
			(layer "F.Fab")
		)
		(fp_line
			(start 0.12065 -0.2794)
			(end 0.12065 -0.3048)
			(stroke
				(width 0.1)
				(type default)
			)
			(layer "F.Fab")
		)
		(fp_line
			(start -0.12065 -0.2794)
			(end 0.12065 -0.2794)
			(stroke
				(width 0.1)
				(type default)
			)
			(layer "F.Fab")
		)
		(fp_line
			(start 0.120396 0.2794)
			(end -0.12065 0.2794)
			(stroke
				(width 0.1)
				(type default)
			)
			(layer "F.Fab")
		)
		(fp_line
			(start -0.12065 0.2794)
			(end -0.12065 0.3048)
			(stroke
				(width 0.1)
				(type default)
			)
			(layer "F.Fab")
		)
		(fp_line
			(start 0.67945 0.3048)
			(end 0.120396 0.3048)
			(stroke
				(width 0.1)
				(type default)
			)
			(layer "F.Fab")
		)
		(fp_line
			(start 0.120396 0.3048)
			(end 0.120396 0.2794)
			(stroke
				(width 0.1)
				(type default)
			)
			(layer "F.Fab")
		)
		(fp_line
			(start -0.12065 0.3048)
			(end -0.67945 0.3048)
			(stroke
				(width 0.1)
				(type default)
			)
			(layer "F.Fab")
		)
		(fp_line
			(start -0.67945 0.3048)
			(end -0.67945 -0.305054)
			(stroke
				(width 0.1)
				(type default)
			)
			(layer "F.Fab")
		)
		(pad "1" smd circle
			(at -0.40005 0 90)
			(size 0 0)
			(layers "F.Cu" "F.Mask" "F.Paste")
			(net "P12V_SSD13_CO_MODE")
		)
		(pad "2" smd circle
			(at 0.40005 0 90)
			(size 0 0)
			(layers "F.Cu" "F.Mask" "F.Paste")
			(net "GND")
		)
	)
	(footprint ""
		(layer "F.Cu")
		(at 115.600226 -118.061486 180)
		(property "Reference" "PC597"
			(at 0 0 180)
			(layer "F.SilkS")
			(hide yes)
			(effects
				(font
					(size 1.27 1.27)
				)
			)
		)
		(property "Value" ""
			(at 0 0 180)
			(layer "F.Fab")
			(effects
				(font
					(size 1.27 1.27)
				)
			)
		)
		(duplicate_pad_numbers_are_jumpers no)
		(fp_line
			(start 0.7874 0.4064)
			(end -0.7874 0.4064)
			(stroke
				(width 0.1524)
				(type default)
			)
			(layer "F.SilkS")
		)
		(fp_line
			(start 0.7874 -0.4064)
			(end 0.7874 0.4064)
			(stroke
				(width 0.1524)
				(type default)
			)
			(layer "F.SilkS")
		)
		(fp_line
			(start -0.7874 0.4064)
			(end -0.7874 -0.4064)
			(stroke
				(width 0.1524)
				(type default)
			)
			(layer "F.SilkS")
		)
		(fp_line
			(start -0.7874 -0.4064)
			(end 0.7874 -0.4064)
			(stroke
				(width 0.1524)
				(type default)
			)
			(layer "F.SilkS")
		)
		(fp_line
			(start 0.67945 0.3048)
			(end 0.120396 0.3048)
			(stroke
				(width 0.1)
				(type default)
			)
			(layer "F.Fab")
		)
		(fp_line
			(start 0.67945 -0.3048)
			(end 0.67945 0.3048)
			(stroke
				(width 0.1)
				(type default)
			)
			(layer "F.Fab")
		)
		(fp_line
			(start 0.12065 -0.2794)
			(end 0.12065 -0.3048)
			(stroke
				(width 0.1)
				(type default)
			)
			(layer "F.Fab")
		)
		(fp_line
			(start 0.12065 -0.3048)
			(end 0.67945 -0.3048)
			(stroke
				(width 0.1)
				(type default)
			)
			(layer "F.Fab")
		)
		(fp_line
			(start 0.120396 0.3048)
			(end 0.120396 0.2794)
			(stroke
				(width 0.1)
				(type default)
			)
			(layer "F.Fab")
		)
		(fp_line
			(start 0.120396 0.2794)
			(end -0.12065 0.2794)
			(stroke
				(width 0.1)
				(type default)
			)
			(layer "F.Fab")
		)
		(fp_line
			(start -0.12065 0.3048)
			(end -0.67945 0.3048)
			(stroke
				(width 0.1)
				(type default)
			)
			(layer "F.Fab")
		)
		(fp_line
			(start -0.12065 0.2794)
			(end -0.12065 0.3048)
			(stroke
				(width 0.1)
				(type default)
			)
			(layer "F.Fab")
		)
		(fp_line
			(start -0.12065 -0.2794)
			(end 0.12065 -0.2794)
			(stroke
				(width 0.1)
				(type default)
			)
			(layer "F.Fab")
		)
		(fp_line
			(start -0.12065 -0.305054)
			(end -0.12065 -0.2794)
			(stroke
				(width 0.1)
				(type default)
			)
			(layer "F.Fab")
		)
		(fp_line
			(start -0.67945 0.3048)
			(end -0.67945 -0.305054)
			(stroke
				(width 0.1)
				(type default)
			)
			(layer "F.Fab")
		)
		(fp_line
			(start -0.67945 -0.305054)
			(end -0.12065 -0.305054)
			(stroke
				(width 0.1)
				(type default)
			)
			(layer "F.Fab")
		)
		(pad "1" smd circle
			(at -0.40005 0 180)
			(size 0 0)
			(layers "F.Cu" "F.Mask" "F.Paste")
			(net "P3V3_CO_DV_DT")
		)
		(pad "2" smd circle
			(at 0.40005 0 180)
			(size 0 0)
			(layers "F.Cu" "F.Mask" "F.Paste")
			(net "GND")
		)
	)
	(footprint ""
		(layer "F.Cu")
		(at 118.882668 -29.875734)
		(property "Reference" "PU123"
			(at -3.226054 -0.215646 90)
			(unlocked yes)
			(layer "F.SilkS")
			(effects
				(font
					(size 0.7874 0.5842)
					(thickness 0.1524)
				)
			)
		)
		(property "Value" ""
			(at 0 0 0)
			(layer "F.Fab")
			(effects
				(font
					(size 1.27 1.27)
				)
			)
		)
		(duplicate_pad_numbers_are_jumpers no)
		(fp_line
			(start -1.239774 -1.495298)
			(end 1.239774 -1.495298)
			(stroke
				(width 0.1524)
				(type default)
			)
			(layer "F.SilkS")
		)
		(fp_line
			(start -1.239774 1.495298)
			(end -1.239774 -1.495298)
			(stroke
				(width 0.1524)
				(type default)
			)
			(layer "F.SilkS")
		)
		(fp_line
			(start 1.239774 -1.495298)
			(end 1.239774 1.495298)
			(stroke
				(width 0.1524)
				(type default)
			)
			(layer "F.SilkS")
		)
		(fp_line
			(start 1.239774 1.495298)
			(end -1.239774 1.495298)
			(stroke
				(width 0.1524)
				(type default)
			)
			(layer "F.SilkS")
		)
		(fp_poly
			(pts
				(xy -2.141474 -1.380744) (xy -2.859786 -0.662432) (xy -1.782064 -0.303276)
			)
			(stroke
				(width 0)
				(type default)
			)
			(fill yes)
			(layer "F.SilkS")
		)
		(fp_line
			(start -0.8001 -1.050036)
			(end 0.8001 -1.050036)
			(stroke
				(width 0.1)
				(type default)
			)
			(layer "F.Fab")
		)
		(fp_line
			(start -0.8001 1.050036)
			(end -0.8001 -1.050036)
			(stroke
				(width 0.1)
				(type default)
			)
			(layer "F.Fab")
		)
		(fp_line
			(start 0.8001 -1.050036)
			(end 0.8001 1.050036)
			(stroke
				(width 0.1)
				(type default)
			)
			(layer "F.Fab")
		)
		(fp_line
			(start 0.8001 1.050036)
			(end -0.8001 1.050036)
			(stroke
				(width 0.1)
				(type default)
			)
			(layer "F.Fab")
		)
		(fp_poly
			(pts
				(xy -2.458974 -0.508) (xy -2.458974 0.508) (xy -1.442974 0)
			)
			(stroke
				(width 0)
				(type default)
			)
			(fill yes)
			(layer "F.Fab")
		)
		(pad "1_2" smd circle
			(at -0.374904 0 90)
			(size 0 0)
			(layers "F.Cu" "F.Mask" "F.Paste")
			(net "P3V3_AUX")
		)
		(pad "3" smd rect
			(at -0.499872 0.999998)
			(size 0.254 0.7112)
			(layers "F.Cu" "F.Mask" "F.Paste")
			(net "GND")
		)
		(pad "4" smd rect
			(at 0 0.999998)
			(size 0.254 0.7112)
			(layers "F.Cu" "F.Mask" "F.Paste")
			(net "P3V3_SSD4_CO_ILIMIT")
		)
		(pad "5" smd rect
			(at 0.499872 0.999998)
			(size 0.254 0.7112)
			(layers "F.Cu" "F.Mask" "F.Paste")
			(net "P3V3_SSD4_CO_MODE")
		)
		(pad "6_7" smd circle
			(at 0.374904 0 270)
			(size 0 0)
			(layers "F.Cu" "F.Mask" "F.Paste")
			(net "P3V3_SSD4")
		)
		(pad "8" smd rect
			(at 0.499872 -0.999998)
			(size 0.254 0.7112)
			(layers "F.Cu" "F.Mask" "F.Paste")
			(net "P3V3_SSD4_CO_GATE")
		)
		(pad "9" smd rect
			(at 0 -0.999998)
			(size 0.254 0.7112)
			(layers "F.Cu" "F.Mask" "F.Paste")
			(net "P3V3_SSD4_CO_EN")
		)
		(pad "10" smd rect
			(at -0.499872 -0.999998)
			(size 0.254 0.7112)
			(layers "F.Cu" "F.Mask" "F.Paste")
			(net "P3V3_SSD4_CO_DV_DT")
		)
	)
	(footprint ""
		(layer "F.Cu")
		(at 403.287484 -370.619528 90)
		(property "Reference" "R6680"
			(at 0 0 90)
			(layer "F.SilkS")
			(hide yes)
			(effects
				(font
					(size 1.27 1.27)
				)
			)
		)
		(property "Value" ""
			(at 0 0 90)
			(layer "F.Fab")
			(effects
				(font
					(size 1.27 1.27)
				)
			)
		)
		(duplicate_pad_numbers_are_jumpers no)
		(fp_line
			(start 0.7874 -0.4064)
			(end 0.7874 0.4064)
			(stroke
				(width 0.1524)
				(type default)
			)
			(layer "F.SilkS")
		)
		(fp_line
			(start -0.7874 -0.4064)
			(end 0.7874 -0.4064)
			(stroke
				(width 0.1524)
				(type default)
			)
			(layer "F.SilkS")
		)
		(fp_line
			(start 0.7874 0.4064)
			(end -0.7874 0.4064)
			(stroke
				(width 0.1524)
				(type default)
			)
			(layer "F.SilkS")
		)
		(fp_line
			(start -0.7874 0.4064)
			(end -0.7874 -0.4064)
			(stroke
				(width 0.1524)
				(type default)
			)
			(layer "F.SilkS")
		)
		(fp_line
			(start -0.12065 -0.305054)
			(end -0.12065 -0.2794)
			(stroke
				(width 0.1)
				(type default)
			)
			(layer "F.Fab")
		)
		(fp_line
			(start -0.67945 -0.305054)
			(end -0.12065 -0.305054)
			(stroke
				(width 0.1)
				(type default)
			)
			(layer "F.Fab")
		)
		(fp_line
			(start 0.67945 -0.3048)
			(end 0.67945 0.3048)
			(stroke
				(width 0.1)
				(type default)
			)
			(layer "F.Fab")
		)
		(fp_line
			(start 0.12065 -0.3048)
			(end 0.67945 -0.3048)
			(stroke
				(width 0.1)
				(type default)
			)
			(layer "F.Fab")
		)
		(fp_line
			(start 0.12065 -0.2794)
			(end 0.12065 -0.3048)
			(stroke
				(width 0.1)
				(type default)
			)
			(layer "F.Fab")
		)
		(fp_line
			(start -0.12065 -0.2794)
			(end 0.12065 -0.2794)
			(stroke
				(width 0.1)
				(type default)
			)
			(layer "F.Fab")
		)
		(fp_line
			(start 0.120396 0.2794)
			(end -0.12065 0.2794)
			(stroke
				(width 0.1)
				(type default)
			)
			(layer "F.Fab")
		)
		(fp_line
			(start -0.12065 0.2794)
			(end -0.12065 0.3048)
			(stroke
				(width 0.1)
				(type default)
			)
			(layer "F.Fab")
		)
		(fp_line
			(start 0.67945 0.3048)
			(end 0.120396 0.3048)
			(stroke
				(width 0.1)
				(type default)
			)
			(layer "F.Fab")
		)
		(fp_line
			(start 0.120396 0.3048)
			(end 0.120396 0.2794)
			(stroke
				(width 0.1)
				(type default)
			)
			(layer "F.Fab")
		)
		(fp_line
			(start -0.12065 0.3048)
			(end -0.67945 0.3048)
			(stroke
				(width 0.1)
				(type default)
			)
			(layer "F.Fab")
		)
		(fp_line
			(start -0.67945 0.3048)
			(end -0.67945 -0.305054)
			(stroke
				(width 0.1)
				(type default)
			)
			(layer "F.Fab")
		)
		(pad "1" smd circle
			(at -0.40005 0 90)
			(size 0 0)
			(layers "F.Cu" "F.Mask" "F.Paste")
			(net "GPU_3V3IO_RSVD1_ISO")
		)
		(pad "2" smd circle
			(at 0.40005 0 90)
			(size 0 0)
			(layers "F.Cu" "F.Mask" "F.Paste")
			(net "GPU_3V3IO_RSVD1")
		)
	)
	(footprint ""
		(layer "F.Cu")
		(at 268.838426 -130.408934)
		(property "Reference" "C461"
			(at 0 0 0)
			(layer "F.SilkS")
			(hide yes)
			(effects
				(font
					(size 1.27 1.27)
				)
			)
		)
		(property "Value" ""
			(at 0 0 0)
			(layer "F.Fab")
			(effects
				(font
					(size 1.27 1.27)
				)
			)
		)
		(duplicate_pad_numbers_are_jumpers no)
		(fp_line
			(start -0.299974 -0.150114)
			(end 0.299974 -0.150114)
			(stroke
				(width 0.1)
				(type default)
			)
			(layer "F.Fab")
		)
		(fp_line
			(start -0.299974 0.150114)
			(end -0.299974 -0.150114)
			(stroke
				(width 0.1)
				(type default)
			)
			(layer "F.Fab")
		)
		(fp_line
			(start 0.299974 -0.150114)
			(end 0.299974 0.150114)
			(stroke
				(width 0.1)
				(type default)
			)
			(layer "F.Fab")
		)
		(fp_line
			(start 0.299974 0.150114)
			(end -0.299974 0.150114)
			(stroke
				(width 0.1)
				(type default)
			)
			(layer "F.Fab")
		)
		(pad "1" smd rect
			(at -0.2667 0)
			(size 0.3048 0.381)
			(layers "F.Cu" "F.Mask" "F.Paste")
			(net "P5E_PEX2_STN1_TX_DP<28>")
		)
		(pad "2" smd rect
			(at 0.2667 0)
			(size 0.3048 0.381)
			(layers "F.Cu" "F.Mask" "F.Paste")
			(net "P5E_PEX2_STN1_TX_C_DP<28>")
		)
	)
)
